# BASEBOARD_FAB2 (Tioga Pass) — schematic netlist excerpt (pin names and nets, part order shuffled) for the footprints in the layout excerpt that follows; sources: Cadence DE-HDL packaged netlist, KiCad conversion of Wiwynn_Tioga_Pass_MB.brd

L8F1  IND-1UH-361-GP  pkg DISCRET-GC1  page 240 : \1\ = VR_P3V3_STBY_PHASE ; \2\ = P3V3_STBY

J9B2  CONN3_C95678002  CONN  pkg PIP  page 156
  IO1  = SMB_SMLINK0_STBY_LVC3_SDA
  IO2  = GND
  IO3  = SMB_SMLINK0_STBY_LVC3_SCL

(kicad_pcb
	(version 20260206)
	(generator "pcbnew")
	(generator_version "10.0")
	(general
		(thickness 1.6)
		(legacy_teardrops no)
	)
	(paper "A4")
	(title_block
		(title "Wiwynn_Tioga_Pass_MB.brd")
		(comment 1 "Tioga Pass / footprints 1938-1939 of 4770")
	)
	(layers
		(0 "F.Cu" signal "TOP")
		(4 "In1.Cu" signal "L2GND")
		(6 "In2.Cu" signal "L3")
		(8 "In3.Cu" signal "L4GND")
		(10 "In4.Cu" signal "L5")
		(12 "In5.Cu" signal "L6GND")
		(14 "In6.Cu" signal "L7VCC")
		(16 "In7.Cu" signal "L8VCC")
		(18 "In8.Cu" signal "L9GND")
		(20 "In9.Cu" signal "L10")
		(22 "In10.Cu" signal "L11GND")
		(24 "In11.Cu" signal "L12")
		(26 "In12.Cu" signal "L13GND")
		(2 "B.Cu" signal "BOTTOM")
		(9 "F.Adhes" user "F.Adhesive")
		(11 "B.Adhes" user "B.Adhesive")
		(13 "F.Paste" user "Package Geometry/Pastemask Top")
		(15 "B.Paste" user "Package Geometry/Pastemask Bottom")
		(5 "F.SilkS" user "Ref Des/Silkscreen Top")
		(7 "B.SilkS" user "Ref Des/Silkscreen Bottom")
		(1 "F.Mask" user "Board Geometry/Soldermask Top")
		(3 "B.Mask" user "Board Geometry/Soldermask Bottom")
		(17 "Dwgs.User" user "User.Drawings")
		(19 "Cmts.User" user "User.Comments")
		(21 "Eco1.User" user "User.Eco1")
		(23 "Eco2.User" user "User.Eco2")
		(25 "Edge.Cuts" user "Board Geometry/Outline")
		(27 "Margin" user)
		(31 "F.CrtYd" user "Package Geometry/Place Bound Top")
		(29 "B.CrtYd" user "Package Geometry/Place Bound Bottom")
		(35 "F.Fab" user "Ref Des/Assembly Top")
		(33 "B.Fab" user "Ref Des/Assembly Bottom")
	)
	(footprint ""
		(layer "F.Cu")
		(at 469.3412 -14.317472 -90)
		(property "Reference" "L8F1"
			(at 0 0 270)
			(layer "F.SilkS")
			(hide yes)
			(effects
				(font
					(size 1.27 1.27)
				)
			)
		)
		(property "Value" "*"
			(at 5.9436 -5.842 270)
			(unlocked yes)
			(layer "F.Fab")
			(hide yes)
			(effects
				(font
					(size 1.27 1.016)
					(thickness 0.1524)
				)
			)
		)
		(property "Device Type" "IND-1UH-361-GP_DISCRET-GC1-INDA"
			(at 5.9436 -7.366 270)
			(unlocked yes)
			(layer "F.Fab")
			(hide yes)
			(effects
				(font
					(size 1.27 1.016)
					(thickness 0.1524)
				)
			)
		)
		(duplicate_pad_numbers_are_jumpers no)
		(fp_line
			(start -4.0005 4.6101)
			(end -4.0005 -4.6101)
			(stroke
				(width 0.1524)
				(type default)
			)
			(layer "F.SilkS")
		)
		(fp_line
			(start 4.0005 4.6101)
			(end -4.0005 4.6101)
			(stroke
				(width 0.1524)
				(type default)
			)
			(layer "F.SilkS")
		)
		(fp_line
			(start -4.0005 -4.6101)
			(end 4.0005 -4.6101)
			(stroke
				(width 0.1524)
				(type default)
			)
			(layer "F.SilkS")
		)
		(fp_line
			(start 4.0005 -4.6101)
			(end 4.0005 4.6101)
			(stroke
				(width 0.1524)
				(type default)
			)
			(layer "F.SilkS")
		)
		(fp_rect
			(start -3.7465 3.5941)
			(end 3.7465 -3.5941)
			(stroke
				(width 0)
				(type default)
			)
			(fill no)
			(layer "F.CrtYd")
		)
		(fp_poly
			(pts
				(xy -4.2545 4.6863) (xy -4.2545 3.5941) (xy 3.7465 3.5941) (xy 3.7465 -3.5941) (xy -3.7465 -3.5941)
				(xy -3.7465 3.5814) (xy -4.2545 3.5814) (xy -4.2545 -4.6863) (xy 4.2545 -4.6863) (xy 4.2545 4.6863)
			)
			(stroke
				(width 0)
				(type default)
			)
			(fill no)
			(layer "F.CrtYd")
		)
		(fp_rect
			(start -4.2545 4.6863)
			(end 4.2545 -4.6863)
			(stroke
				(width 0)
				(type default)
			)
			(fill no)
			(layer "F.Fab")
		)
		(pad "1" smd rect
			(at 0 -3.039872 270)
			(size 5.5118 2.6416)
			(layers "F.Cu" "F.Mask" "F.Paste")
			(net "VR_P3V3_STBY_PHASE")
		)
		(pad "2" smd rect
			(at 0 3.039872 270)
			(size 5.5118 2.6416)
			(layers "F.Cu" "F.Mask" "F.Paste")
			(net "P3V3_STBY")
		)
	)
	(footprint ""
		(layer "F.Cu")
		(at 483.6414 -125.222 -90)
		(property "Reference" "J9B2"
			(at 2.69367 0.889 0)
			(unlocked yes)
			(layer "B.SilkS")
			(effects
				(font
					(size 0.7874 0.5842)
					(thickness 0.1524)
				)
				(justify left mirror)
			)
		)
		(property "Value" ""
			(at 0 0 270)
			(layer "F.Fab")
			(effects
				(font
					(size 1.27 1.27)
				)
			)
		)
		(duplicate_pad_numbers_are_jumpers no)
		(fp_line
			(start -1.27 6.54939)
			(end -1.27 -1.46939)
			(stroke
				(width 0.1524)
				(type default)
			)
			(layer "F.SilkS")
		)
		(fp_line
			(start 1.27 6.54939)
			(end -1.27 6.54939)
			(stroke
				(width 0.1524)
				(type default)
			)
			(layer "F.SilkS")
		)
		(fp_line
			(start -1.27 -1.46939)
			(end 1.27 -1.46939)
			(stroke
				(width 0.1524)
				(type default)
			)
			(layer "F.SilkS")
		)
		(fp_line
			(start 1.27 -1.46939)
			(end 1.27 6.54939)
			(stroke
				(width 0.1524)
				(type default)
			)
			(layer "F.SilkS")
		)
		(fp_poly
			(pts
				(xy -3.17246 0.38862) (xy -3.17246 -0.62738) (xy -1.90246 -0.11938)
			)
			(stroke
				(width 0)
				(type default)
			)
			(fill yes)
			(layer "F.SilkS")
		)
		(fp_poly
			(pts
				(xy -3.17246 0.38862) (xy -3.17246 -0.62738) (xy -1.90246 -0.11938)
			)
			(stroke
				(width 0)
				(type default)
			)
			(fill yes)
			(layer "B.SilkS")
		)
		(fp_poly
			(pts
				(xy 1.27 6.54939) (xy 1.27 -1.46939) (xy -1.27 -1.46939) (xy -1.27 6.54939)
			)
			(stroke
				(width 0)
				(type default)
			)
			(fill no)
			(layer "F.CrtYd")
		)
		(fp_poly
			(pts
				(xy -3.17246 0.38862) (xy -3.17246 -0.62738) (xy -1.90246 -0.11938)
			)
			(stroke
				(width 0)
				(type default)
			)
			(fill yes)
			(layer "B.Fab")
		)
		(fp_line
			(start -1.27 6.54939)
			(end -1.27 -1.46939)
			(stroke
				(width 0.1)
				(type default)
			)
			(layer "F.Fab")
		)
		(fp_line
			(start 1.27 6.54939)
			(end -1.27 6.54939)
			(stroke
				(width 0.1)
				(type default)
			)
			(layer "F.Fab")
		)
		(fp_line
			(start -1.27 -1.46939)
			(end 1.27 -1.46939)
			(stroke
				(width 0.1)
				(type default)
			)
			(layer "F.Fab")
		)
		(fp_line
			(start 1.27 -1.46939)
			(end 1.27 6.54939)
			(stroke
				(width 0.1)
				(type default)
			)
			(layer "F.Fab")
		)
		(fp_poly
			(pts
				(xy -3.17246 0.38862) (xy -3.17246 -0.62738) (xy -1.90246 -0.11938)
			)
			(stroke
				(width 0)
				(type default)
			)
			(fill yes)
			(layer "F.Fab")
		)
		(fp_text user "3"
			(at 0.188976 7.44728 0)
			(unlocked yes)
			(layer "F.SilkS")
			(effects
				(font
					(size 0.7874 0.5842)
					(thickness 0.1524)
				)
				(justify left)
			)
		)
		(fp_text user "3"
			(at -1.60655 3.38582 0)
			(unlocked yes)
			(layer "B.SilkS")
			(effects
				(font
					(size 0.7874 0.5842)
					(thickness 0.1524)
				)
				(justify left mirror)
			)
		)
		(fp_text user "3"
			(at -1.82626 5.08127 270)
			(unlocked yes)
			(layer "B.Fab")
			(effects
				(font
					(size 0.7874 0.5842)
					(thickness 0.1524)
				)
				(justify left mirror)
			)
		)
		(fp_text user "3"
			(at 0.187706 7.4422 0)
			(unlocked yes)
			(layer "F.Fab")
			(effects
				(font
					(size 0.7874 0.5842)
					(thickness 0.1524)
				)
				(justify left)
			)
		)
		(pad "1" thru_hole rect
			(at 0 0 270)
			(size 1.524 1.524)
			(drill 1.143)
			(layers "*.Cu" "*.Mask")
			(remove_unused_layers no)
			(net "SMB_SMLINK0_STBY_LVC3_SDA")
			(clearance 0.127)
			(thermal_gap 0.127)
			(padstack
				(mode front_inner_back)
				(layer "Inner"
					(shape circle)
					(size 1.524 1.524)
					(clearance 0.127)
				)
				(layer "B.Cu"
					(shape rect)
					(size 1.524 1.524)
					(clearance 0.127)
				)
			)
		)
		(pad "2" thru_hole circle
			(at 0 2.54 270)
			(size 1.524 1.524)
			(drill 1.143)
			(layers "*.Cu" "*.Mask")
			(remove_unused_layers no)
			(net "GND")
			(clearance 0.127)
			(thermal_gap 0.127)
		)
		(pad "3" thru_hole circle
			(at 0 5.08 270)
			(size 1.524 1.524)
			(drill 1.143)
			(layers "*.Cu" "*.Mask")
			(remove_unused_layers no)
			(net "SMB_SMLINK0_STBY_LVC3_SCL")
			(clearance 0.127)
			(thermal_gap 0.127)
		)
	)
)
